# S9S_MB_2U (Grand Teton) — schematic netlist excerpt (pin names and nets, part order shuffled) for the footprints in the layout excerpt that follows; sources: Cadence DE-HDL packaged netlist, KiCad conversion of 03242023_DA0F0TMBIJ0_F0T_Motherboard_J_brd_V01_OCP.brd

J25  SCONN288_ADR50017P130CC  SCONN288_ADR50017-P130CC IO  pkg DDR288S_1-1VXB  page 106
  VIN_BULK0  = P12V_S3_AUX_CPU1_NVDIMM
  RFU0  = TP_CHE_CPU1_DIMM1_FRU_0
  VIN_MGMT  = P3V3_AUX
  HSCL  = I3C_SPD_DDREFGH_CPU1_LVC1_SCL_R
  HSDA  = I3C_SPD_DDREFGH_CPU1_LVC1_SDA
  VSS0  = GND
  DQ0_A  = M_E_CPU1_SA_DQ<0>
  VSS1  = GND
  DQ1_A  = M_E_CPU1_SA_DQ<1>
  VSS2  = GND
  DQS0_A_T  = M_E_CPU1_SA_DQS_DP<0>
  DQS0_A_C  = M_E_CPU1_SA_DQS_DN<0>
  VSS3  = GND
  DQ4_A  = M_E_CPU1_SA_DQ<4>
  VSS4  = GND
  DQ5_A  = M_E_CPU1_SA_DQ<5>
  VSS5  = GND
  DQ8_A  = M_E_CPU1_SA_DQ<8>
  VSS6  = GND
  DQ9_A  = M_E_CPU1_SA_DQ<9>
  VSS7  = GND
  DQS1_A_T  = M_E_CPU1_SA_DQS_DP<1>
  DQS1_A_C  = M_E_CPU1_SA_DQS_DN<1>
  VSS8  = GND
  DQ12_A  = M_E_CPU1_SA_DQ<12>
  VSS9  = GND
  DQ13_A  = M_E_CPU1_SA_DQ<13>
  VSS10  = GND
  DQ16_A  = M_E_CPU1_SA_DQ<16>
  VSS11  = GND
  DQ17_A  = M_E_CPU1_SA_DQ<17>
  VSS12  = GND
  DQS2_A_T  = M_E_CPU1_SA_DQS_DP<2>
  DQS2_A_C  = M_E_CPU1_SA_DQS_DN<2>
  VSS13  = GND
  DQ20_A  = M_E_CPU1_SA_DQ<20>
  VSS14  = GND
  DQ21_A  = M_E_CPU1_SA_DQ<21>
  VSS15  = GND
  DQ24_A  = M_E_CPU1_SA_DQ<24>
  VSS16  = GND
  DQ25_A  = M_E_CPU1_SA_DQ<25>
  VSS17  = GND
  DQS3_A_T  = M_E_CPU1_SA_DQS_DP<3>
  DQS3_A_C  = M_E_CPU1_SA_DQS_DN<3>
  VSS18  = GND
  DQ28_A  = M_E_CPU1_SA_DQ<28>
  VSS19  = GND
  DQ29_A  = M_E_CPU1_SA_DQ<29>
  VSS20  = GND
  CB0_A  = M_E_CPU1_SA_CB<0>
  VSS21  = GND
  CB1_A  = M_E_CPU1_SA_CB<1>
  VSS22  = GND
  DQS4_A_T  = M_E_CPU1_SA_DQS_DP<4>
  DQS4_A_C  = M_E_CPU1_SA_DQS_DN<4>
  VSS23  = GND
  CB4_A  = M_E_CPU1_SA_CB<4>
  VSS24  = GND
  CB5_A  = M_E_CPU1_SA_CB<5>
  VSS25  = GND
  ALERT_N  = M_E_CPU1_ALERT_N
  VSS26  = GND
  CS0_A_N  = M_E_CPU1_SA_CS_N<0>
  VSS27  = GND
  CA0_A  = M_E_CPU1_SA_CA<0>
  VSS28  = GND
  CA2_A  = M_E_CPU1_SA_CA<2>
  VSS29  = GND
  CA4_A  = M_E_CPU1_SA_CA<4>
  VSS30  = GND
  CA6_A  = M_E_CPU1_SA_CA<6>
  VSS31  = GND
  PAR_A  = M_E_CPU1_SA_PAR
  VSS32  = GND
  CA0_B  = M_E_CPU1_SB_CA<0>
  VSS33  = GND
  CA2_B  = M_E_CPU1_SB_CA<2>
  VSS34  = GND
  CA4_B  = M_E_CPU1_SB_CA<4>
  VSS35  = GND
  CA6_B  = M_E_CPU1_SB_CA<6>
  VSS36  = GND
  CS0_B_N  = M_E_CPU1_SB_CS_N<0>
  VSS37  = GND
  \lbd||rsp_a_n\  = M_E_CPU1_SA_RSP<0>
  \lbs||rsp_b_n\  = M_E_CPU1_SB_RSP<0>
  VSS38  = GND
  CB4_B  = M_E_CPU1_SB_CB<4>
  VSS39  = GND
  CB5_B  = M_E_CPU1_SB_CB<5>
  VSS40  = GND
  \dqs9_b_t||tdqs9_b_t||dbi4_b_n\  = M_E_CPU1_SB_DQS_DP<9>
  \dqs9_b_c||tdqs9_b_c\  = M_E_CPU1_SB_DQS_DN<9>
  VSS41  = GND
  CB0_B  = M_E_CPU1_SB_CB<0>
  VSS42  = GND
  CB1_B  = M_E_CPU1_SB_CB<1>
  VSS43  = GND
  DQ0_B  = M_E_CPU1_SB_DQ<0>
  VSS44  = GND
  DQ1_B  = M_E_CPU1_SB_DQ<1>
  VSS45  = GND
  DQS0_B_T  = M_E_CPU1_SB_DQS_DP<0>
  DQS0_B_C  = M_E_CPU1_SB_DQS_DN<0>
  VSS46  = GND
  DQ4_B  = M_E_CPU1_SB_DQ<4>
  VSS47  = GND
  DQ5_B  = M_E_CPU1_SB_DQ<5>
  VSS48  = GND
  DQ8_B  = M_E_CPU1_SB_DQ<8>
  VSS49  = GND
  DQ9_B  = M_E_CPU1_SB_DQ<9>
  VSS50  = GND
  DQS1_B_T  = M_E_CPU1_SB_DQS_DP<1>
  DQS1_B_C  = M_E_CPU1_SB_DQS_DN<1>
  VSS51  = GND
  DQ12_B  = M_E_CPU1_SB_DQ<12>
  VSS52  = GND
  DQ13_B  = M_E_CPU1_SB_DQ<13>
  VSS53  = GND
  DQ16_B  = M_E_CPU1_SB_DQ<16>
  VSS54  = GND
  DQ17_B  = M_E_CPU1_SB_DQ<17>
  VSS55  = GND
  DQS2_B_T  = M_E_CPU1_SB_DQS_DP<2>
  DQS2_B_C  = M_E_CPU1_SB_DQS_DN<2>
  VSS56  = GND
  DQ20_B  = M_E_CPU1_SB_DQ<20>
  VSS57  = GND
  DQ21_B  = M_E_CPU1_SB_DQ<21>
  VSS58  = GND
  DQ24_B  = M_E_CPU1_SB_DQ<24>
  VSS59  = GND
  DQ25_B  = M_E_CPU1_SB_DQ<25>
  VSS60  = GND
  DQS3_B_T  = M_E_CPU1_SB_DQS_DP<3>
  DQS3_B_C  = M_E_CPU1_SB_DQS_DN<3>
  VSS61  = GND
  DQ28_B  = M_E_CPU1_SB_DQ<28>
  VSS62  = GND
  DQ29_B  = M_E_CPU1_SB_DQ<29>
  VSS63  = GND
  RFU1  = TP_CHE_CPU1_DIMM1_FRU_1
  VIN_BULK1  = P12V_S3_AUX_CPU1_NVDIMM
  VIN_BULK2  = P12V_S3_AUX_CPU1_NVDIMM
  \pwr_good||fail_n\  = PWRGD_CHE_CPU1_DIMM1
  HSA  = PD_CHE_CPU1_DIMM1_SAA
  RFU2  = TP_CHE_CPU1_DIMM1_FRU_2
  RFU3  = TP_CHE_CPU1_DIMM1_FRU_3
  VSS64  = GND
  DQ2_A  = M_E_CPU1_SA_DQ<2>
  VSS65  = GND
  DQ3_A  = M_E_CPU1_SA_DQ<3>
  VSS66  = GND
  \dqs5_a_c||tdqs5_a_c||dqs5_a_t||tdqs5_a_t\  = M_E_CPU1_SA_DQS_DN<5>
  \dqs5_a_t||tdqs5_a_t\  = M_E_CPU1_SA_DQS_DP<5>
  VSS67  = GND
  DQ6_A  = M_E_CPU1_SA_DQ<6>
  VSS68  = GND
  DQ7_A  = M_E_CPU1_SA_DQ<7>
  VSS69  = GND
  DQ10_A  = M_E_CPU1_SA_DQ<10>
  VSS70  = GND
  DQ11_A  = M_E_CPU1_SA_DQ<11>
  VSS71  = GND
  \dqs6_a_c||tdqs6_a_c||dqs6_a_t||tdqs6_a_t\  = M_E_CPU1_SA_DQS_DN<6>
  \dqs6_a_t||tdqs6_a_t\  = M_E_CPU1_SA_DQS_DP<6>
  VSS72  = GND
  DQ14_A  = M_E_CPU1_SA_DQ<14>
  VSS73  = GND
  DQ15_A  = M_E_CPU1_SA_DQ<15>
  VSS74  = GND
  DQ18_A  = M_E_CPU1_SA_DQ<18>
  VSS75  = GND
  DQ19_A  = M_E_CPU1_SA_DQ<19>
  VSS76  = GND
  \dqs7_a_c||tdqs7_a_c\  = M_E_CPU1_SA_DQS_DN<7>
  \dqs7_a_t||tdqs7_a_t\  = M_E_CPU1_SA_DQS_DP<7>
  VSS77  = GND
  DQ22_A  = M_E_CPU1_SA_DQ<22>
  VSS78  = GND
  DQ23_A  = M_E_CPU1_SA_DQ<23>
  VSS79  = GND
  DQ26_A  = M_E_CPU1_SA_DQ<26>
  VSS80  = GND
  DQ27_A  = M_E_CPU1_SA_DQ<27>
  VSS81  = GND
  \dqs8_a_c||tdqs8_a_c\  = M_E_CPU1_SA_DQS_DN<8>
  \dqs8_a_t||tdqs8_a_t\  = M_E_CPU1_SA_DQS_DP<8>
  VSS82  = GND
  DQ30_A  = M_E_CPU1_SA_DQ<30>
  VSS83  = GND
  DQ31_A  = M_E_CPU1_SA_DQ<31>
  VSS84  = GND
  CB2_A  = M_E_CPU1_SA_CB<2>
  VSS85  = GND
  CB3_A  = M_E_CPU1_SA_CB<3>
  VSS86  = GND
  \dqs9_a_c||tdqs9_a_c\  = M_E_CPU1_SA_DQS_DN<9>
  \dqs9_a_t||tdqs9_a_t\  = M_E_CPU1_SA_DQS_DP<9>
  VSS87  = GND
  CB6_A  = M_E_CPU1_SA_CB<6>
  VSS88  = GND
  CB7_A  = M_E_CPU1_SA_CB<7>
  VSS89  = GND
  RESET_N  = RST_M_EF_CPU1_FPGA_N
  VSS90  = GND
  CS1_A_N  = M_E_CPU1_SA_CS_N<1>
  VSS91  = GND
  CA1_A  = M_E_CPU1_SA_CA<1>
  VSS92  = GND
  CA3_A  = M_E_CPU1_SA_CA<3>
  VSS93  = GND
  CA5_A  = M_E_CPU1_SA_CA<5>
  VSS94  = GND
  CK_T  = M_E_CPU1_CLK_DP<0>
  CK_C  = M_E_CPU1_CLK_DN<0>
  VSS95  = GND
  RFU4  = TP_CHE_CPU1_DIMM1_FRU_4
  CA1_B  = M_E_CPU1_SB_CA<1>
  VSS96  = GND
  CA3_B  = M_E_CPU1_SB_CA<3>
  VSS97  = GND
  CA5_B  = M_E_CPU1_SB_CA<5>
  VSS98  = GND
  PAR_B  = M_E_CPU1_SB_PAR
  VSS99  = GND
  CS1_B_N  = M_E_CPU1_SB_CS_N<1>
  VSS100  = GND
  RFU5  = TP_CHE_CPU1_DIMM1_FRU_5
  RFU6  = TP_CHE_CPU1_DIMM1_FRU_6
  VSS101  = GND
  CB6_B  = M_E_CPU1_SB_CB<6>
  VSS102  = GND
  CB7_B  = M_E_CPU1_SB_CB<7>
  VSS103  = GND
  DQS4_B_C  = M_E_CPU1_SB_DQS_DN<4>
  DQS4_B_T  = M_E_CPU1_SB_DQS_DP<4>
  VSS104  = GND
  CB2_B  = M_E_CPU1_SB_CB<2>
  VSS105  = GND
  CB3_B  = M_E_CPU1_SB_CB<3>
  VSS106  = GND
  DQ2_B  = M_E_CPU1_SB_DQ<2>
  VSS107  = GND
  DQ3_B  = M_E_CPU1_SB_DQ<3>
  VSS108  = GND
  \dqs5_b_c||tdqs5_b_c\  = M_E_CPU1_SB_DQS_DN<5>
  \dqs5_b_t||tdqs5_b_t\  = M_E_CPU1_SB_DQS_DP<5>
  VSS109  = GND
  DQ6_B  = M_E_CPU1_SB_DQ<6>
  VSS110  = GND
  DQ7_B  = M_E_CPU1_SB_DQ<7>
  VSS111  = GND
  DQ10_B  = M_E_CPU1_SB_DQ<10>
  VSS112  = GND
  DQ11_B  = M_E_CPU1_SB_DQ<11>
  VSS113  = GND
  \dqs6_b_c||tdqs6_b_c\  = M_E_CPU1_SB_DQS_DN<6>
  \dqs6_b_t||tdqs6_b_t\  = M_E_CPU1_SB_DQS_DP<6>
  VSS114  = GND
  DQ14_B  = M_E_CPU1_SB_DQ<14>
  VSS115  = GND
  DQ15_B  = M_E_CPU1_SB_DQ<15>
  VSS116  = GND
  DQ18_B  = M_E_CPU1_SB_DQ<18>
  VSS117  = GND
  DQ19_B  = M_E_CPU1_SB_DQ<19>
  VSS118  = GND
  \dqs7_b_c||tdqs7_b_c\  = M_E_CPU1_SB_DQS_DN<7>
  \dqs7_b_t||tdqs7_b_t\  = M_E_CPU1_SB_DQS_DP<7>
  VSS119  = GND
  DQ22_B  = M_E_CPU1_SB_DQ<22>
  VSS120  = GND
  DQ23_B  = M_E_CPU1_SB_DQ<23>
  VSS121  = GND
  DQ26_B  = M_E_CPU1_SB_DQ<26>
  VSS122  = GND
  DQ27_B  = M_E_CPU1_SB_DQ<27>
  VSS123  = GND
  \dqs8_b_c||tdqs8_b_c\  = M_E_CPU1_SB_DQS_DN<8>
  \dqs8_b_t||tdqs8_b_t\  = M_E_CPU1_SB_DQS_DP<8>
  VSS124  = GND
  DQ30_B  = M_E_CPU1_SB_DQ<30>
  VSS125  = GND
  DQ31_B  = M_E_CPU1_SB_DQ<31>
  VSS126  = GND
  G1  = GND
  G2  = GND
  G3  = GND

(kicad_pcb
	(version 20260206)
	(generator "pcbnew")
	(generator_version "10.0")
	(general
		(thickness 1.6)
		(legacy_teardrops no)
	)
	(paper "A4")
	(title_block
		(title "03242023_DA0F0TMBIJ0_F0T_Motherboard_J_brd_V01_OCP.brd")
		(comment 1 "Grand Teton / footprint 2539 of 6105 (J25), pads 1-45 of 291")
	)
	(layers
		(0 "F.Cu" signal "TOP")
		(4 "In1.Cu" signal "GND")
		(6 "In2.Cu" signal "IN1")
		(8 "In3.Cu" signal "GND1")
		(10 "In4.Cu" signal "IN2")
		(12 "In5.Cu" signal "GND2")
		(14 "In6.Cu" signal "IN3")
		(16 "In7.Cu" signal "GND3")
		(18 "In8.Cu" signal "VCC")
		(20 "In9.Cu" signal "VCC1")
		(22 "In10.Cu" signal "GND4")
		(24 "In11.Cu" signal "IN4")
		(26 "In12.Cu" signal "GND5")
		(28 "In13.Cu" signal "IN5")
		(30 "In14.Cu" signal "GND6")
		(32 "In15.Cu" signal "IN6")
		(34 "In16.Cu" signal "GND7")
		(2 "B.Cu" signal "BOTTOM")
		(9 "F.Adhes" user "F.Adhesive")
		(11 "B.Adhes" user "B.Adhesive")
		(13 "F.Paste" user "Package Geometry/Pastemask Top")
		(15 "B.Paste" user "Package Geometry/Pastemask Bottom")
		(5 "F.SilkS" user "Ref Des/Silkscreen Top")
		(7 "B.SilkS" user "Ref Des/Silkscreen Bottom")
		(1 "F.Mask" user "Board Geometry/Soldermask Top")
		(3 "B.Mask" user "Board Geometry/Soldermask Bottom")
		(17 "Dwgs.User" user "User.Drawings")
		(19 "Cmts.User" user "User.Comments")
		(21 "Eco1.User" user "User.Eco1")
		(23 "Eco2.User" user "User.Eco2")
		(25 "Edge.Cuts" user "Board Geometry/Outline")
		(27 "Margin" user)
		(31 "F.CrtYd" user "Package Geometry/Place Bound Top")
		(29 "B.CrtYd" user "Package Geometry/Place Bound Bottom")
		(35 "F.Fab" user "Ref Des/Assembly Top")
		(33 "B.Fab" user "Ref Des/Assembly Bottom")
	)
	(footprint ""
		(layer "F.Cu")
		(at 168.40708 -258.091686)
		(property "Reference" "J25"
			(at -3.683 -81.702148 0)
			(unlocked yes)
			(layer "F.SilkS")
			(effects
				(font
					(size 0.7874 0.5842)
					(thickness 0.1524)
				)
				(justify left)
			)
		)
		(property "Value" ""
			(at 0 0 0)
			(layer "F.Fab")
			(effects
				(font
					(size 1.27 1.27)
				)
			)
		)
		(duplicate_pad_numbers_are_jumpers no)
		(pad "1" smd rect
			(at -2.050034 -63.324994 270)
			(size 0.519938 1.4986)
			(layers "F.Cu" "F.Mask" "F.Paste")
			(net "P12V_S3_AUX_CPU1_NVDIMM")
		)
		(pad "2" smd rect
			(at -2.050034 -62.47511 270)
			(size 0.519938 1.4986)
			(layers "F.Cu" "F.Mask" "F.Paste")
			(net "TP_CHE_CPU1_DIMM1_FRU_0")
		)
		(pad "3" smd rect
			(at -2.050034 -61.624972 270)
			(size 0.519938 1.4986)
			(layers "F.Cu" "F.Mask" "F.Paste")
			(net "P3V3_AUX")
		)
		(pad "4" smd rect
			(at -2.050034 -60.775088 270)
			(size 0.519938 1.4986)
			(layers "F.Cu" "F.Mask" "F.Paste")
			(net "I3C_SPD_DDREFGH_CPU1_LVC1_SCL_R")
		)
		(pad "5" smd rect
			(at -2.050034 -59.92495 270)
			(size 0.519938 1.4986)
			(layers "F.Cu" "F.Mask" "F.Paste")
			(net "I3C_SPD_DDREFGH_CPU1_LVC1_SDA")
		)
		(pad "6" smd rect
			(at -2.050034 -59.075066 270)
			(size 0.519938 1.4986)
			(layers "F.Cu" "F.Mask" "F.Paste")
			(net "GND")
		)
		(pad "7" smd rect
			(at -2.050034 -58.224928 270)
			(size 0.519938 1.4986)
			(layers "F.Cu" "F.Mask" "F.Paste")
			(net "M_E_CPU1_SA_DQ<0>")
		)
		(pad "8" smd rect
			(at -2.050034 -57.375044 270)
			(size 0.519938 1.4986)
			(layers "F.Cu" "F.Mask" "F.Paste")
			(net "GND")
		)
		(pad "9" smd rect
			(at -2.050034 -56.524906 270)
			(size 0.519938 1.4986)
			(layers "F.Cu" "F.Mask" "F.Paste")
			(net "M_E_CPU1_SA_DQ<1>")
		)
		(pad "10" smd rect
			(at -2.050034 -55.675022 270)
			(size 0.519938 1.4986)
			(layers "F.Cu" "F.Mask" "F.Paste")
			(net "GND")
		)
		(pad "11" smd rect
			(at -2.050034 -54.824884 270)
			(size 0.519938 1.4986)
			(layers "F.Cu" "F.Mask" "F.Paste")
			(net "M_E_CPU1_SA_DQS_DP<0>")
		)
		(pad "12" smd rect
			(at -2.050034 -53.975 270)
			(size 0.519938 1.4986)
			(layers "F.Cu" "F.Mask" "F.Paste")
			(net "M_E_CPU1_SA_DQS_DN<0>")
		)
		(pad "13" smd rect
			(at -2.050034 -53.125116 270)
			(size 0.519938 1.4986)
			(layers "F.Cu" "F.Mask" "F.Paste")
			(net "GND")
		)
		(pad "14" smd rect
			(at -2.050034 -52.274978 270)
			(size 0.519938 1.4986)
			(layers "F.Cu" "F.Mask" "F.Paste")
			(net "M_E_CPU1_SA_DQ<4>")
		)
		(pad "15" smd rect
			(at -2.050034 -51.425094 270)
			(size 0.519938 1.4986)
			(layers "F.Cu" "F.Mask" "F.Paste")
			(net "GND")
		)
		(pad "16" smd rect
			(at -2.050034 -50.574956 270)
			(size 0.519938 1.4986)
			(layers "F.Cu" "F.Mask" "F.Paste")
			(net "M_E_CPU1_SA_DQ<5>")
		)
		(pad "17" smd rect
			(at -2.050034 -49.725072 270)
			(size 0.519938 1.4986)
			(layers "F.Cu" "F.Mask" "F.Paste")
			(net "GND")
		)
		(pad "18" smd rect
			(at -2.050034 -48.874934 270)
			(size 0.519938 1.4986)
			(layers "F.Cu" "F.Mask" "F.Paste")
			(net "M_E_CPU1_SA_DQ<8>")
		)
		(pad "19" smd rect
			(at -2.050034 -48.02505 270)
			(size 0.519938 1.4986)
			(layers "F.Cu" "F.Mask" "F.Paste")
			(net "GND")
		)
		(pad "20" smd rect
			(at -2.050034 -47.174912 270)
			(size 0.519938 1.4986)
			(layers "F.Cu" "F.Mask" "F.Paste")
			(net "M_E_CPU1_SA_DQ<9>")
		)
		(pad "21" smd rect
			(at -2.050034 -46.325028 270)
			(size 0.519938 1.4986)
			(layers "F.Cu" "F.Mask" "F.Paste")
			(net "GND")
		)
		(pad "22" smd rect
			(at -2.050034 -45.47489 270)
			(size 0.519938 1.4986)
			(layers "F.Cu" "F.Mask" "F.Paste")
			(net "M_E_CPU1_SA_DQS_DP<1>")
		)
		(pad "23" smd rect
			(at -2.050034 -44.625006 270)
			(size 0.519938 1.4986)
			(layers "F.Cu" "F.Mask" "F.Paste")
			(net "M_E_CPU1_SA_DQS_DN<1>")
		)
		(pad "24" smd rect
			(at -2.050034 -43.775122 270)
			(size 0.519938 1.4986)
			(layers "F.Cu" "F.Mask" "F.Paste")
			(net "GND")
		)
		(pad "25" smd rect
			(at -2.050034 -42.924984 270)
			(size 0.519938 1.4986)
			(layers "F.Cu" "F.Mask" "F.Paste")
			(net "M_E_CPU1_SA_DQ<12>")
		)
		(pad "26" smd rect
			(at -2.050034 -42.0751 270)
			(size 0.519938 1.4986)
			(layers "F.Cu" "F.Mask" "F.Paste")
			(net "GND")
		)
		(pad "27" smd rect
			(at -2.050034 -41.224962 270)
			(size 0.519938 1.4986)
			(layers "F.Cu" "F.Mask" "F.Paste")
			(net "M_E_CPU1_SA_DQ<13>")
		)
		(pad "28" smd rect
			(at -2.050034 -40.375078 270)
			(size 0.519938 1.4986)
			(layers "F.Cu" "F.Mask" "F.Paste")
			(net "GND")
		)
		(pad "29" smd rect
			(at -2.050034 -39.52494 270)
			(size 0.519938 1.4986)
			(layers "F.Cu" "F.Mask" "F.Paste")
			(net "M_E_CPU1_SA_DQ<16>")
		)
		(pad "30" smd rect
			(at -2.050034 -38.675056 270)
			(size 0.519938 1.4986)
			(layers "F.Cu" "F.Mask" "F.Paste")
			(net "GND")
		)
		(pad "31" smd rect
			(at -2.050034 -37.824918 270)
			(size 0.519938 1.4986)
			(layers "F.Cu" "F.Mask" "F.Paste")
			(net "M_E_CPU1_SA_DQ<17>")
		)
		(pad "32" smd rect
			(at -2.050034 -36.975034 270)
			(size 0.519938 1.4986)
			(layers "F.Cu" "F.Mask" "F.Paste")
			(net "GND")
		)
		(pad "33" smd rect
			(at -2.050034 -36.124896 270)
			(size 0.519938 1.4986)
			(layers "F.Cu" "F.Mask" "F.Paste")
			(net "M_E_CPU1_SA_DQS_DP<2>")
		)
		(pad "34" smd rect
			(at -2.050034 -35.275012 270)
			(size 0.519938 1.4986)
			(layers "F.Cu" "F.Mask" "F.Paste")
			(net "M_E_CPU1_SA_DQS_DN<2>")
		)
		(pad "35" smd rect
			(at -2.050034 -34.425128 270)
			(size 0.519938 1.4986)
			(layers "F.Cu" "F.Mask" "F.Paste")
			(net "GND")
		)
		(pad "36" smd rect
			(at -2.050034 -33.57499 270)
			(size 0.519938 1.4986)
			(layers "F.Cu" "F.Mask" "F.Paste")
			(net "M_E_CPU1_SA_DQ<20>")
		)
		(pad "37" smd rect
			(at -2.050034 -32.725106 270)
			(size 0.519938 1.4986)
			(layers "F.Cu" "F.Mask" "F.Paste")
			(net "GND")
		)
		(pad "38" smd rect
			(at -2.050034 -31.874968 270)
			(size 0.519938 1.4986)
			(layers "F.Cu" "F.Mask" "F.Paste")
			(net "M_E_CPU1_SA_DQ<21>")
		)
		(pad "39" smd rect
			(at -2.050034 -31.025084 270)
			(size 0.519938 1.4986)
			(layers "F.Cu" "F.Mask" "F.Paste")
			(net "GND")
		)
		(pad "40" smd rect
			(at -2.050034 -30.174946 270)
			(size 0.519938 1.4986)
			(layers "F.Cu" "F.Mask" "F.Paste")
			(net "M_E_CPU1_SA_DQ<24>")
		)
		(pad "41" smd rect
			(at -2.050034 -29.325062 270)
			(size 0.519938 1.4986)
			(layers "F.Cu" "F.Mask" "F.Paste")
			(net "GND")
		)
		(pad "42" smd rect
			(at -2.050034 -28.474924 270)
			(size 0.519938 1.4986)
			(layers "F.Cu" "F.Mask" "F.Paste")
			(net "M_E_CPU1_SA_DQ<25>")
		)
		(pad "43" smd rect
			(at -2.050034 -27.62504 270)
			(size 0.519938 1.4986)
			(layers "F.Cu" "F.Mask" "F.Paste")
			(net "GND")
		)
		(pad "44" smd rect
			(at -2.050034 -26.774902 270)
			(size 0.519938 1.4986)
			(layers "F.Cu" "F.Mask" "F.Paste")
			(net "M_E_CPU1_SA_DQS_DP<3>")
		)
		(pad "45" smd rect
			(at -2.050034 -25.925018 270)
			(size 0.519938 1.4986)
			(layers "F.Cu" "F.Mask" "F.Paste")
			(net "M_E_CPU1_SA_DQS_DN<3>")
		)
	)
)
